(kicad_pcb
	(version 20260206)
	(generator "pcbnew")
	(generator_version "10.0")
	(general
		(thickness 1.6)
		(legacy_teardrops no)
	)
	(paper "A4")
	(title_block
		(title "04192023_DAF0TMB3IC0_F0TG_MB_C_brd_V02_OCP.brd")
		(comment 1 "Grand Teton / footprints 1992-1998 of 8354")
	)
	(layers
		(0 "F.Cu" signal "TOP")
		(4 "In1.Cu" signal "GND")
		(6 "In2.Cu" signal "IN1")
		(8 "In3.Cu" signal "GND1")
		(10 "In4.Cu" signal "IN2")
		(12 "In5.Cu" signal "GND2")
		(14 "In6.Cu" signal "IN3")
		(16 "In7.Cu" signal "GND3")
		(18 "In8.Cu" signal "VCC")
		(20 "In9.Cu" signal "VCC1")
		(22 "In10.Cu" signal "GND4")
		(24 "In11.Cu" signal "IN4")
		(26 "In12.Cu" signal "GND5")
		(28 "In13.Cu" signal "IN5")
		(30 "In14.Cu" signal "GND6")
		(32 "In15.Cu" signal "IN6")
		(34 "In16.Cu" signal "GND7")
		(2 "B.Cu" signal "BOTTOM")
		(9 "F.Adhes" user "F.Adhesive")
		(11 "B.Adhes" user "B.Adhesive")
		(13 "F.Paste" user "Package Geometry/Pastemask Top")
		(15 "B.Paste" user "Package Geometry/Pastemask Bottom")
		(5 "F.SilkS" user "Ref Des/Silkscreen Top")
		(7 "B.SilkS" user "Ref Des/Silkscreen Bottom")
		(1 "F.Mask" user "Board Geometry/Soldermask Top")
		(3 "B.Mask" user "Board Geometry/Soldermask Bottom")
		(17 "Dwgs.User" user "User.Drawings")
		(19 "Cmts.User" user "User.Comments")
		(21 "Eco1.User" user "User.Eco1")
		(23 "Eco2.User" user "User.Eco2")
		(25 "Edge.Cuts" user "Board Geometry/Outline")
		(27 "Margin" user)
		(31 "F.CrtYd" user "Package Geometry/Place Bound Top")
		(29 "B.CrtYd" user "Package Geometry/Place Bound Bottom")
		(35 "F.Fab" user "Ref Des/Assembly Top")
		(33 "B.Fab" user "Ref Des/Assembly Bottom")
	)
	(footprint ""
		(layer "F.Cu")
		(at 223.378522 -74.510138 180)
		(property "Reference" "PC2213"
			(at 0 0 180)
			(layer "F.SilkS")
			(hide yes)
			(effects
				(font
					(size 1.27 1.27)
				)
			)
		)
		(property "Value" ""
			(at 0 0 180)
			(layer "F.Fab")
			(effects
				(font
					(size 1.27 1.27)
				)
			)
		)
		(duplicate_pad_numbers_are_jumpers no)
		(fp_line
			(start 0.7874 0.4064)
			(end -0.7874 0.4064)
			(stroke
				(width 0.1524)
				(type default)
			)
			(layer "F.SilkS")
		)
		(fp_line
			(start 0.7874 -0.4064)
			(end 0.7874 0.4064)
			(stroke
				(width 0.1524)
				(type default)
			)
			(layer "F.SilkS")
		)
		(fp_line
			(start -0.7874 0.4064)
			(end -0.7874 -0.4064)
			(stroke
				(width 0.1524)
				(type default)
			)
			(layer "F.SilkS")
		)
		(fp_line
			(start -0.7874 -0.4064)
			(end 0.7874 -0.4064)
			(stroke
				(width 0.1524)
				(type default)
			)
			(layer "F.SilkS")
		)
		(fp_line
			(start 0.67945 0.3048)
			(end 0.120396 0.3048)
			(stroke
				(width 0.1)
				(type default)
			)
			(layer "F.Fab")
		)
		(fp_line
			(start 0.67945 -0.3048)
			(end 0.67945 0.3048)
			(stroke
				(width 0.1)
				(type default)
			)
			(layer "F.Fab")
		)
		(fp_line
			(start 0.12065 -0.2794)
			(end 0.12065 -0.3048)
			(stroke
				(width 0.1)
				(type default)
			)
			(layer "F.Fab")
		)
		(fp_line
			(start 0.12065 -0.3048)
			(end 0.67945 -0.3048)
			(stroke
				(width 0.1)
				(type default)
			)
			(layer "F.Fab")
		)
		(fp_line
			(start 0.120396 0.3048)
			(end 0.120396 0.2794)
			(stroke
				(width 0.1)
				(type default)
			)
			(layer "F.Fab")
		)
		(fp_line
			(start 0.120396 0.2794)
			(end -0.12065 0.2794)
			(stroke
				(width 0.1)
				(type default)
			)
			(layer "F.Fab")
		)
		(fp_line
			(start -0.12065 0.3048)
			(end -0.67945 0.3048)
			(stroke
				(width 0.1)
				(type default)
			)
			(layer "F.Fab")
		)
		(fp_line
			(start -0.12065 0.2794)
			(end -0.12065 0.3048)
			(stroke
				(width 0.1)
				(type default)
			)
			(layer "F.Fab")
		)
		(fp_line
			(start -0.12065 -0.2794)
			(end 0.12065 -0.2794)
			(stroke
				(width 0.1)
				(type default)
			)
			(layer "F.Fab")
		)
		(fp_line
			(start -0.12065 -0.305054)
			(end -0.12065 -0.2794)
			(stroke
				(width 0.1)
				(type default)
			)
			(layer "F.Fab")
		)
		(fp_line
			(start -0.67945 0.3048)
			(end -0.67945 -0.305054)
			(stroke
				(width 0.1)
				(type default)
			)
			(layer "F.Fab")
		)
		(fp_line
			(start -0.67945 -0.305054)
			(end -0.12065 -0.305054)
			(stroke
				(width 0.1)
				(type default)
			)
			(layer "F.Fab")
		)
		(pad "1" smd circle
			(at -0.40005 0 180)
			(size 0 0)
			(layers "F.Cu" "F.Mask" "F.Paste")
			(net "P3V3_E1S_0_R")
		)
		(pad "2" smd circle
			(at 0.40005 0 180)
			(size 0 0)
			(layers "F.Cu" "F.Mask" "F.Paste")
			(net "P3V3_E1S_GATE_0")
		)
	)
	(footprint ""
		(layer "F.Cu")
		(at 22.479 -357.632 180)
		(property "Reference" "PR217"
			(at 0 0 180)
			(layer "F.SilkS")
			(hide yes)
			(effects
				(font
					(size 1.27 1.27)
				)
			)
		)
		(property "Value" ""
			(at 0 0 180)
			(layer "F.Fab")
			(effects
				(font
					(size 1.27 1.27)
				)
			)
		)
		(duplicate_pad_numbers_are_jumpers no)
		(fp_line
			(start 0.7874 0.4064)
			(end -0.7874 0.4064)
			(stroke
				(width 0.1524)
				(type default)
			)
			(layer "F.SilkS")
		)
		(fp_line
			(start 0.7874 -0.4064)
			(end 0.7874 0.4064)
			(stroke
				(width 0.1524)
				(type default)
			)
			(layer "F.SilkS")
		)
		(fp_line
			(start -0.7874 0.4064)
			(end -0.7874 -0.4064)
			(stroke
				(width 0.1524)
				(type default)
			)
			(layer "F.SilkS")
		)
		(fp_line
			(start -0.7874 -0.4064)
			(end 0.7874 -0.4064)
			(stroke
				(width 0.1524)
				(type default)
			)
			(layer "F.SilkS")
		)
		(fp_line
			(start 0.67945 0.3048)
			(end 0.120396 0.3048)
			(stroke
				(width 0.1)
				(type default)
			)
			(layer "F.Fab")
		)
		(fp_line
			(start 0.67945 -0.3048)
			(end 0.67945 0.3048)
			(stroke
				(width 0.1)
				(type default)
			)
			(layer "F.Fab")
		)
		(fp_line
			(start 0.12065 -0.2794)
			(end 0.12065 -0.3048)
			(stroke
				(width 0.1)
				(type default)
			)
			(layer "F.Fab")
		)
		(fp_line
			(start 0.12065 -0.3048)
			(end 0.67945 -0.3048)
			(stroke
				(width 0.1)
				(type default)
			)
			(layer "F.Fab")
		)
		(fp_line
			(start 0.120396 0.3048)
			(end 0.120396 0.2794)
			(stroke
				(width 0.1)
				(type default)
			)
			(layer "F.Fab")
		)
		(fp_line
			(start 0.120396 0.2794)
			(end -0.12065 0.2794)
			(stroke
				(width 0.1)
				(type default)
			)
			(layer "F.Fab")
		)
		(fp_line
			(start -0.12065 0.3048)
			(end -0.67945 0.3048)
			(stroke
				(width 0.1)
				(type default)
			)
			(layer "F.Fab")
		)
		(fp_line
			(start -0.12065 0.2794)
			(end -0.12065 0.3048)
			(stroke
				(width 0.1)
				(type default)
			)
			(layer "F.Fab")
		)
		(fp_line
			(start -0.12065 -0.2794)
			(end 0.12065 -0.2794)
			(stroke
				(width 0.1)
				(type default)
			)
			(layer "F.Fab")
		)
		(fp_line
			(start -0.12065 -0.305054)
			(end -0.12065 -0.2794)
			(stroke
				(width 0.1)
				(type default)
			)
			(layer "F.Fab")
		)
		(fp_line
			(start -0.67945 0.3048)
			(end -0.67945 -0.305054)
			(stroke
				(width 0.1)
				(type default)
			)
			(layer "F.Fab")
		)
		(fp_line
			(start -0.67945 -0.305054)
			(end -0.12065 -0.305054)
			(stroke
				(width 0.1)
				(type default)
			)
			(layer "F.Fab")
		)
		(pad "1" smd circle
			(at -0.40005 0 180)
			(size 0 0)
			(layers "F.Cu" "F.Mask" "F.Paste")
			(net "SVID_PVDDCR_CPU1_P1_SVTI")
		)
		(pad "2" smd circle
			(at 0.40005 0 180)
			(size 0 0)
			(layers "F.Cu" "F.Mask" "F.Paste")
			(net "GND")
		)
	)
	(footprint ""
		(layer "F.Cu")
		(at 273.35734 -123.896628 180)
		(property "Reference" "R4270"
			(at 0 0 180)
			(layer "F.SilkS")
			(hide yes)
			(effects
				(font
					(size 1.27 1.27)
				)
			)
		)
		(property "Value" ""
			(at 0 0 180)
			(layer "F.Fab")
			(effects
				(font
					(size 1.27 1.27)
				)
			)
		)
		(duplicate_pad_numbers_are_jumpers no)
		(fp_line
			(start 0.7874 0.4064)
			(end -0.7874 0.4064)
			(stroke
				(width 0.1524)
				(type default)
			)
			(layer "F.SilkS")
		)
		(fp_line
			(start 0.7874 -0.4064)
			(end 0.7874 0.4064)
			(stroke
				(width 0.1524)
				(type default)
			)
			(layer "F.SilkS")
		)
		(fp_line
			(start -0.7874 0.4064)
			(end -0.7874 -0.4064)
			(stroke
				(width 0.1524)
				(type default)
			)
			(layer "F.SilkS")
		)
		(fp_line
			(start -0.7874 -0.4064)
			(end 0.7874 -0.4064)
			(stroke
				(width 0.1524)
				(type default)
			)
			(layer "F.SilkS")
		)
		(fp_line
			(start 0.67945 0.3048)
			(end 0.120396 0.3048)
			(stroke
				(width 0.1)
				(type default)
			)
			(layer "F.Fab")
		)
		(fp_line
			(start 0.67945 -0.3048)
			(end 0.67945 0.3048)
			(stroke
				(width 0.1)
				(type default)
			)
			(layer "F.Fab")
		)
		(fp_line
			(start 0.12065 -0.2794)
			(end 0.12065 -0.3048)
			(stroke
				(width 0.1)
				(type default)
			)
			(layer "F.Fab")
		)
		(fp_line
			(start 0.12065 -0.3048)
			(end 0.67945 -0.3048)
			(stroke
				(width 0.1)
				(type default)
			)
			(layer "F.Fab")
		)
		(fp_line
			(start 0.120396 0.3048)
			(end 0.120396 0.2794)
			(stroke
				(width 0.1)
				(type default)
			)
			(layer "F.Fab")
		)
		(fp_line
			(start 0.120396 0.2794)
			(end -0.12065 0.2794)
			(stroke
				(width 0.1)
				(type default)
			)
			(layer "F.Fab")
		)
		(fp_line
			(start -0.12065 0.3048)
			(end -0.67945 0.3048)
			(stroke
				(width 0.1)
				(type default)
			)
			(layer "F.Fab")
		)
		(fp_line
			(start -0.12065 0.2794)
			(end -0.12065 0.3048)
			(stroke
				(width 0.1)
				(type default)
			)
			(layer "F.Fab")
		)
		(fp_line
			(start -0.12065 -0.2794)
			(end 0.12065 -0.2794)
			(stroke
				(width 0.1)
				(type default)
			)
			(layer "F.Fab")
		)
		(fp_line
			(start -0.12065 -0.305054)
			(end -0.12065 -0.2794)
			(stroke
				(width 0.1)
				(type default)
			)
			(layer "F.Fab")
		)
		(fp_line
			(start -0.67945 0.3048)
			(end -0.67945 -0.305054)
			(stroke
				(width 0.1)
				(type default)
			)
			(layer "F.Fab")
		)
		(fp_line
			(start -0.67945 -0.305054)
			(end -0.12065 -0.305054)
			(stroke
				(width 0.1)
				(type default)
			)
			(layer "F.Fab")
		)
		(pad "1" smd circle
			(at -0.40005 0 180)
			(size 0 0)
			(layers "F.Cu" "F.Mask" "F.Paste")
			(net "P3V3_AUX")
		)
		(pad "2" smd circle
			(at 0.40005 0 180)
			(size 0 0)
			(layers "F.Cu" "F.Mask" "F.Paste")
			(net "SMB_VR_SENSOR_3V3AUX_SDA")
		)
	)
	(footprint ""
		(layer "F.Cu")
		(at 445.19088 -97.269808 180)
		(property "Reference" "R3600"
			(at 0 0 180)
			(layer "F.SilkS")
			(hide yes)
			(effects
				(font
					(size 1.27 1.27)
				)
			)
		)
		(property "Value" ""
			(at 0 0 180)
			(layer "F.Fab")
			(effects
				(font
					(size 1.27 1.27)
				)
			)
		)
		(duplicate_pad_numbers_are_jumpers no)
		(fp_line
			(start 0.7874 0.4064)
			(end -0.7874 0.4064)
			(stroke
				(width 0.1524)
				(type default)
			)
			(layer "F.SilkS")
		)
		(fp_line
			(start 0.7874 -0.4064)
			(end 0.7874 0.4064)
			(stroke
				(width 0.1524)
				(type default)
			)
			(layer "F.SilkS")
		)
		(fp_line
			(start -0.7874 0.4064)
			(end -0.7874 -0.4064)
			(stroke
				(width 0.1524)
				(type default)
			)
			(layer "F.SilkS")
		)
		(fp_line
			(start -0.7874 -0.4064)
			(end 0.7874 -0.4064)
			(stroke
				(width 0.1524)
				(type default)
			)
			(layer "F.SilkS")
		)
		(fp_line
			(start 0.67945 0.3048)
			(end 0.120396 0.3048)
			(stroke
				(width 0.1)
				(type default)
			)
			(layer "F.Fab")
		)
		(fp_line
			(start 0.67945 -0.3048)
			(end 0.67945 0.3048)
			(stroke
				(width 0.1)
				(type default)
			)
			(layer "F.Fab")
		)
		(fp_line
			(start 0.12065 -0.2794)
			(end 0.12065 -0.3048)
			(stroke
				(width 0.1)
				(type default)
			)
			(layer "F.Fab")
		)
		(fp_line
			(start 0.12065 -0.3048)
			(end 0.67945 -0.3048)
			(stroke
				(width 0.1)
				(type default)
			)
			(layer "F.Fab")
		)
		(fp_line
			(start 0.120396 0.3048)
			(end 0.120396 0.2794)
			(stroke
				(width 0.1)
				(type default)
			)
			(layer "F.Fab")
		)
		(fp_line
			(start 0.120396 0.2794)
			(end -0.12065 0.2794)
			(stroke
				(width 0.1)
				(type default)
			)
			(layer "F.Fab")
		)
		(fp_line
			(start -0.12065 0.3048)
			(end -0.67945 0.3048)
			(stroke
				(width 0.1)
				(type default)
			)
			(layer "F.Fab")
		)
		(fp_line
			(start -0.12065 0.2794)
			(end -0.12065 0.3048)
			(stroke
				(width 0.1)
				(type default)
			)
			(layer "F.Fab")
		)
		(fp_line
			(start -0.12065 -0.2794)
			(end 0.12065 -0.2794)
			(stroke
				(width 0.1)
				(type default)
			)
			(layer "F.Fab")
		)
		(fp_line
			(start -0.12065 -0.305054)
			(end -0.12065 -0.2794)
			(stroke
				(width 0.1)
				(type default)
			)
			(layer "F.Fab")
		)
		(fp_line
			(start -0.67945 0.3048)
			(end -0.67945 -0.305054)
			(stroke
				(width 0.1)
				(type default)
			)
			(layer "F.Fab")
		)
		(fp_line
			(start -0.67945 -0.305054)
			(end -0.12065 -0.305054)
			(stroke
				(width 0.1)
				(type default)
			)
			(layer "F.Fab")
		)
		(pad "1" smd circle
			(at -0.40005 0 180)
			(size 0 0)
			(layers "F.Cu" "F.Mask" "F.Paste")
			(net "SMB_INA230_1_3V3AUX_SCL_R")
		)
		(pad "2" smd circle
			(at 0.40005 0 180)
			(size 0 0)
			(layers "F.Cu" "F.Mask" "F.Paste")
			(net "SMB_INA230_1_3V3AUX_SCL_R1")
		)
	)
	(footprint ""
		(layer "F.Cu")
		(at 358.268524 -385.364228)
		(property "Reference" "C937"
			(at 0 0 0)
			(layer "F.SilkS")
			(hide yes)
			(effects
				(font
					(size 1.27 1.27)
				)
			)
		)
		(property "Value" ""
			(at 0 0 0)
			(layer "F.Fab")
			(effects
				(font
					(size 1.27 1.27)
				)
			)
		)
		(duplicate_pad_numbers_are_jumpers no)
		(fp_line
			(start -0.299974 -0.150114)
			(end 0.299974 -0.150114)
			(stroke
				(width 0.1)
				(type default)
			)
			(layer "F.Fab")
		)
		(fp_line
			(start -0.299974 0.150114)
			(end -0.299974 -0.150114)
			(stroke
				(width 0.1)
				(type default)
			)
			(layer "F.Fab")
		)
		(fp_line
			(start 0.299974 -0.150114)
			(end 0.299974 0.150114)
			(stroke
				(width 0.1)
				(type default)
			)
			(layer "F.Fab")
		)
		(fp_line
			(start 0.299974 0.150114)
			(end -0.299974 0.150114)
			(stroke
				(width 0.1)
				(type default)
			)
			(layer "F.Fab")
		)
		(pad "1" smd rect
			(at -0.2667 0)
			(size 0.3048 0.381)
			(layers "F.Cu" "F.Mask" "F.Paste")
			(net "P5E_CPU0_P1_TX_C_DP<14>")
		)
		(pad "2" smd rect
			(at 0.2667 0)
			(size 0.3048 0.381)
			(layers "F.Cu" "F.Mask" "F.Paste")
			(net "P5E_CPU0_P1_TX_DP<14>")
		)
	)
	(footprint ""
		(layer "F.Cu")
		(at 172.54347 -415.503868 180)
		(property "Reference" "C9001"
			(at 0 0 180)
			(layer "F.SilkS")
			(hide yes)
			(effects
				(font
					(size 1.27 1.27)
				)
			)
		)
		(property "Value" ""
			(at 0 0 180)
			(layer "F.Fab")
			(effects
				(font
					(size 1.27 1.27)
				)
			)
		)
		(duplicate_pad_numbers_are_jumpers no)
		(fp_line
			(start 0.7874 0.4064)
			(end -0.7874 0.4064)
			(stroke
				(width 0.1524)
				(type default)
			)
			(layer "F.SilkS")
		)
		(fp_line
			(start 0.7874 -0.4064)
			(end 0.7874 0.4064)
			(stroke
				(width 0.1524)
				(type default)
			)
			(layer "F.SilkS")
		)
		(fp_line
			(start -0.7874 0.4064)
			(end -0.7874 -0.4064)
			(stroke
				(width 0.1524)
				(type default)
			)
			(layer "F.SilkS")
		)
		(fp_line
			(start -0.7874 -0.4064)
			(end 0.7874 -0.4064)
			(stroke
				(width 0.1524)
				(type default)
			)
			(layer "F.SilkS")
		)
		(fp_line
			(start 0.67945 0.3048)
			(end 0.120396 0.3048)
			(stroke
				(width 0.1)
				(type default)
			)
			(layer "F.Fab")
		)
		(fp_line
			(start 0.67945 -0.3048)
			(end 0.67945 0.3048)
			(stroke
				(width 0.1)
				(type default)
			)
			(layer "F.Fab")
		)
		(fp_line
			(start 0.12065 -0.2794)
			(end 0.12065 -0.3048)
			(stroke
				(width 0.1)
				(type default)
			)
			(layer "F.Fab")
		)
		(fp_line
			(start 0.12065 -0.3048)
			(end 0.67945 -0.3048)
			(stroke
				(width 0.1)
				(type default)
			)
			(layer "F.Fab")
		)
		(fp_line
			(start 0.120396 0.3048)
			(end 0.120396 0.2794)
			(stroke
				(width 0.1)
				(type default)
			)
			(layer "F.Fab")
		)
		(fp_line
			(start 0.120396 0.2794)
			(end -0.12065 0.2794)
			(stroke
				(width 0.1)
				(type default)
			)
			(layer "F.Fab")
		)
		(fp_line
			(start -0.12065 0.3048)
			(end -0.67945 0.3048)
			(stroke
				(width 0.1)
				(type default)
			)
			(layer "F.Fab")
		)
		(fp_line
			(start -0.12065 0.2794)
			(end -0.12065 0.3048)
			(stroke
				(width 0.1)
				(type default)
			)
			(layer "F.Fab")
		)
		(fp_line
			(start -0.12065 -0.2794)
			(end 0.12065 -0.2794)
			(stroke
				(width 0.1)
				(type default)
			)
			(layer "F.Fab")
		)
		(fp_line
			(start -0.12065 -0.305054)
			(end -0.12065 -0.2794)
			(stroke
				(width 0.1)
				(type default)
			)
			(layer "F.Fab")
		)
		(fp_line
			(start -0.67945 0.3048)
			(end -0.67945 -0.305054)
			(stroke
				(width 0.1)
				(type default)
			)
			(layer "F.Fab")
		)
		(fp_line
			(start -0.67945 -0.305054)
			(end -0.12065 -0.305054)
			(stroke
				(width 0.1)
				(type default)
			)
			(layer "F.Fab")
		)
		(pad "1" smd circle
			(at -0.40005 0 180)
			(size 0 0)
			(layers "F.Cu" "F.Mask" "F.Paste")
			(net "PRSNT_CABLE_SWB_B2_ISO_N")
		)
		(pad "2" smd circle
			(at 0.40005 0 180)
			(size 0 0)
			(layers "F.Cu" "F.Mask" "F.Paste")
			(net "GND")
		)
	)
	(footprint ""
		(layer "F.Cu")
		(at 334.028288 -403.818852 -90)
		(property "Reference" "R1039"
			(at 0 0 270)
			(layer "F.SilkS")
			(hide yes)
			(effects
				(font
					(size 1.27 1.27)
				)
			)
		)
		(property "Value" ""
			(at 0 0 270)
			(layer "F.Fab")
			(effects
				(font
					(size 1.27 1.27)
				)
			)
		)
		(duplicate_pad_numbers_are_jumpers no)
		(fp_line
			(start -0.32512 0.175006)
			(end -0.32512 -0.175006)
			(stroke
				(width 0.1)
				(type default)
			)
			(layer "F.Fab")
		)
		(fp_line
			(start 0.32512 0.175006)
			(end -0.32512 0.175006)
			(stroke
				(width 0.1)
				(type default)
			)
			(layer "F.Fab")
		)
		(fp_line
			(start -0.32512 -0.175006)
			(end 0.32512 -0.175006)
			(stroke
				(width 0.1)
				(type default)
			)
			(layer "F.Fab")
		)
		(fp_line
			(start 0.32512 -0.175006)
			(end 0.32512 0.175006)
			(stroke
				(width 0.1)
				(type default)
			)
			(layer "F.Fab")
		)
		(pad "1" smd rect
			(at -0.2667 0 270)
			(size 0.3048 0.381)
			(layers "F.Cu" "F.Mask" "F.Paste")
			(net "P1V8_CPU0_RT_1D")
		)
		(pad "2" smd rect
			(at 0.2667 0 90)
			(size 0.3048 0.381)
			(layers "F.Cu" "F.Mask" "F.Paste")
			(net "MODE_RT_CPU0_P1")
		)
	)
)
